# BASEBOARD_FAB2 (Tioga Pass) — schematic netlist excerpt (pin names and nets, part order shuffled) for the footprints in the layout excerpt that follows; sources: Cadence DE-HDL packaged netlist, KiCad conversion of Wiwynn_Tioga_Pass_MB.brd

C2P2  CAP_A  0.1UF 16V 10% X7R  pkg 0402V  page 192 : A = P3V3_STBY ; B = GND
R4R4  RES  150.0 1% CHIP  pkg 0402  page 97 : A = PVCCIO_CPU0 ; B = H_CPU0_FAST_WAKE_N
C6R2  CAP_A  22.0UF 4V 20% X6S  pkg 0603V  page 204 : A = PVCCIN_CPU0 ; B = GND

(kicad_pcb
	(version 20260206)
	(generator "pcbnew")
	(generator_version "10.0")
	(general
		(thickness 1.6)
		(legacy_teardrops no)
	)
	(paper "A4")
	(title_block
		(title "Wiwynn_Tioga_Pass_MB.brd")
		(comment 1 "Tioga Pass / footprints 2958-2960 of 4770")
	)
	(layers
		(0 "F.Cu" signal "TOP")
		(4 "In1.Cu" signal "L2GND")
		(6 "In2.Cu" signal "L3")
		(8 "In3.Cu" signal "L4GND")
		(10 "In4.Cu" signal "L5")
		(12 "In5.Cu" signal "L6GND")
		(14 "In6.Cu" signal "L7VCC")
		(16 "In7.Cu" signal "L8VCC")
		(18 "In8.Cu" signal "L9GND")
		(20 "In9.Cu" signal "L10")
		(22 "In10.Cu" signal "L11GND")
		(24 "In11.Cu" signal "L12")
		(26 "In12.Cu" signal "L13GND")
		(2 "B.Cu" signal "BOTTOM")
		(9 "F.Adhes" user "F.Adhesive")
		(11 "B.Adhes" user "B.Adhesive")
		(13 "F.Paste" user "Package Geometry/Pastemask Top")
		(15 "B.Paste" user "Package Geometry/Pastemask Bottom")
		(5 "F.SilkS" user "Ref Des/Silkscreen Top")
		(7 "B.SilkS" user "Ref Des/Silkscreen Bottom")
		(1 "F.Mask" user "Board Geometry/Soldermask Top")
		(3 "B.Mask" user "Board Geometry/Soldermask Bottom")
		(17 "Dwgs.User" user "User.Drawings")
		(19 "Cmts.User" user "User.Comments")
		(21 "Eco1.User" user "User.Eco1")
		(23 "Eco2.User" user "User.Eco2")
		(25 "Edge.Cuts" user "Board Geometry/Outline")
		(27 "Margin" user)
		(31 "F.CrtYd" user "Package Geometry/Place Bound Top")
		(29 "B.CrtYd" user "Package Geometry/Place Bound Bottom")
		(35 "F.Fab" user "Ref Des/Assembly Top")
		(33 "B.Fab" user "Ref Des/Assembly Bottom")
	)
	(footprint ""
		(layer "B.Cu")
		(at 214.503 -63.11392)
		(property "Reference" "C6R2"
			(at 0 0 0)
			(layer "B.SilkS")
			(hide yes)
			(effects
				(font
					(size 1.27 1.27)
				)
				(justify mirror)
			)
		)
		(property "Value" ""
			(at 0 0 0)
			(layer "B.Fab")
			(effects
				(font
					(size 1.27 1.27)
				)
				(justify mirror)
			)
		)
		(duplicate_pad_numbers_are_jumpers no)
		(fp_poly
			(pts
				(xy 0.4953 -0.2032) (xy -0.4953 -0.2032) (xy -0.4953 1.6002) (xy 0.4953 1.6002)
			)
			(stroke
				(width 0)
				(type default)
			)
			(fill no)
			(layer "B.CrtYd")
		)
		(fp_line
			(start -0.4953 -0.2032)
			(end -0.4953 1.6002)
			(stroke
				(width 0.1)
				(type default)
			)
			(layer "B.Fab")
		)
		(fp_line
			(start -0.4953 1.6002)
			(end 0.4953 1.6002)
			(stroke
				(width 0.1)
				(type default)
			)
			(layer "B.Fab")
		)
		(fp_line
			(start 0.4953 -0.2032)
			(end -0.4953 -0.2032)
			(stroke
				(width 0.1)
				(type default)
			)
			(layer "B.Fab")
		)
		(fp_line
			(start 0.4953 1.6002)
			(end 0.4953 -0.2032)
			(stroke
				(width 0.1)
				(type default)
			)
			(layer "B.Fab")
		)
		(pad "1" smd rect
			(at 0 0 180)
			(size 0.762 0.889)
			(layers "B.Cu" "B.Mask" "B.Paste")
			(net "PVCCIN_CPU0")
		)
		(pad "2" smd rect
			(at 0 1.397 180)
			(size 0.762 0.889)
			(layers "B.Cu" "B.Mask" "B.Paste")
			(net "GND")
		)
		(zone
			(layer "B.Cu")
			(hatch none 0.5)
			(connect_pads
				(clearance 0)
			)
			(min_thickness 0.25)
			(keepout
				(tracks not_allowed)
				(vias allowed)
				(pads allowed)
				(copperpour not_allowed)
				(footprints allowed)
			)
			(placement
				(enabled no)
				(sheetname "")
			)
			(fill
				(thermal_gap 0.5)
				(thermal_bridge_width 0.5)
				(island_removal_mode 0)
			)
			(polygon
				(pts
					(xy 214.884 -62.66942) (xy 214.122 -62.66942) (xy 214.122 -62.16142) (xy 214.884 -62.16142)
				)
			)
		)
	)
	(footprint ""
		(layer "B.Cu")
		(at 375.544842 -77.894434)
		(property "Reference" "C2P2"
			(at 0 0 0)
			(layer "B.SilkS")
			(hide yes)
			(effects
				(font
					(size 1.27 1.27)
				)
				(justify mirror)
			)
		)
		(property "Value" ""
			(at 0 0 0)
			(layer "B.Fab")
			(effects
				(font
					(size 1.27 1.27)
				)
				(justify mirror)
			)
		)
		(duplicate_pad_numbers_are_jumpers no)
		(fp_rect
			(start 0.2794 0.9144)
			(end -0.2794 -0.1143)
			(stroke
				(width 0)
				(type default)
			)
			(fill no)
			(layer "B.CrtYd")
		)
		(fp_line
			(start -0.2794 -0.1143)
			(end -0.2794 0.9144)
			(stroke
				(width 0.1)
				(type default)
			)
			(layer "B.Fab")
		)
		(fp_line
			(start -0.2794 0.9144)
			(end 0.2794 0.9144)
			(stroke
				(width 0.1)
				(type default)
			)
			(layer "B.Fab")
		)
		(fp_line
			(start 0.2794 -0.1143)
			(end -0.2794 -0.1143)
			(stroke
				(width 0.1)
				(type default)
			)
			(layer "B.Fab")
		)
		(fp_line
			(start 0.2794 0.9144)
			(end 0.2794 -0.1143)
			(stroke
				(width 0.1)
				(type default)
			)
			(layer "B.Fab")
		)
		(pad "1" smd custom
			(at 0 0 270)
			(size 0.10414 0.10414)
			(layers "B.Cu" "B.Mask" "B.Paste")
			(net "P3V3_STBY")
			(options
				(clearance outline)
				(anchor circle)
			)
			(primitives
				(gr_poly
					(pts
						(xy -0.20828 -0.08636) (xy -0.20828 0.08636) (xy -0.08636 0.20828) (xy 0.086614 0.20828) (xy 0.20828 0.086614)
						(xy 0.20828 -0.08636) (xy 0.08636 -0.20828) (xy -0.08636 -0.20828)
					)
					(width 0)
					(fill yes)
				)
			)
		)
		(pad "2" smd custom
			(at 0 0.8001 270)
			(size 0.10414 0.10414)
			(layers "B.Cu" "B.Mask" "B.Paste")
			(net "GND")
			(options
				(clearance outline)
				(anchor circle)
			)
			(primitives
				(gr_poly
					(pts
						(xy -0.20828 -0.08636) (xy -0.20828 0.08636) (xy -0.08636 0.20828) (xy 0.086614 0.20828) (xy 0.20828 0.086614)
						(xy 0.20828 -0.08636) (xy 0.08636 -0.20828) (xy -0.08636 -0.20828)
					)
					(width 0)
					(fill yes)
				)
			)
		)
		(zone
			(layer "B.Cu")
			(hatch none 0.5)
			(connect_pads
				(clearance 0)
			)
			(min_thickness 0.25)
			(keepout
				(tracks not_allowed)
				(vias allowed)
				(pads allowed)
				(copperpour not_allowed)
				(footprints allowed)
			)
			(placement
				(enabled no)
				(sheetname "")
			)
			(fill
				(thermal_gap 0.5)
				(thermal_bridge_width 0.5)
				(island_removal_mode 0)
			)
			(polygon
				(pts
					(xy 375.632472 -77.684884) (xy 375.632472 -77.303884) (xy 375.457212 -77.303884) (xy 375.456958 -77.684884)
				)
			)
		)
		(zone
			(layer "B.Cu")
			(hatch none 0.5)
			(connect_pads
				(clearance 0)
			)
			(min_thickness 0.25)
			(keepout
				(tracks allowed)
				(vias not_allowed)
				(pads allowed)
				(copperpour not_allowed)
				(footprints allowed)
			)
			(placement
				(enabled no)
				(sheetname "")
			)
			(fill
				(thermal_gap 0.5)
				(thermal_bridge_width 0.5)
				(island_removal_mode 0)
			)
			(polygon
				(pts
					(xy 375.632472 -77.684884) (xy 375.632472 -77.303884) (xy 375.457212 -77.303884) (xy 375.456958 -77.684884)
				)
			)
		)
	)
	(footprint ""
		(layer "B.Cu")
		(at 327.914 -61.087 -90)
		(property "Reference" "R4R4"
			(at 0 0 90)
			(layer "B.SilkS")
			(hide yes)
			(effects
				(font
					(size 1.27 1.27)
				)
				(justify mirror)
			)
		)
		(property "Value" ""
			(at 0 0 90)
			(layer "B.Fab")
			(effects
				(font
					(size 1.27 1.27)
				)
				(justify mirror)
			)
		)
		(duplicate_pad_numbers_are_jumpers no)
		(fp_poly
			(pts
				(xy 0.2794 -0.1016) (xy -0.2794 -0.1016) (xy -0.2794 0.9906) (xy 0.2794 0.9906)
			)
			(stroke
				(width 0)
				(type default)
			)
			(fill no)
			(layer "B.CrtYd")
		)
		(fp_line
			(start -0.2794 0.9906)
			(end -0.2794 -0.1016)
			(stroke
				(width 0.1)
				(type default)
			)
			(layer "B.Fab")
		)
		(fp_line
			(start 0.2794 0.9906)
			(end -0.2794 0.9906)
			(stroke
				(width 0.1)
				(type default)
			)
			(layer "B.Fab")
		)
		(fp_line
			(start -0.2794 -0.1016)
			(end 0.2794 -0.1016)
			(stroke
				(width 0.1)
				(type default)
			)
			(layer "B.Fab")
		)
		(fp_line
			(start 0.2794 -0.1016)
			(end 0.2794 0.9906)
			(stroke
				(width 0.1)
				(type default)
			)
			(layer "B.Fab")
		)
		(pad "1" smd rect
			(at 0 0 90)
			(size 0.508 0.508)
			(layers "B.Cu" "B.Mask" "B.Paste")
			(net "PVCCIO_CPU0")
		)
		(pad "2" smd rect
			(at 0 0.889 90)
			(size 0.508 0.508)
			(layers "B.Cu" "B.Mask" "B.Paste")
			(net "H_CPU0_FAST_WAKE_N")
		)
		(zone
			(layer "B.Cu")
			(hatch none 0.5)
			(connect_pads
				(clearance 0)
			)
			(min_thickness 0.25)
			(keepout
				(tracks not_allowed)
				(vias allowed)
				(pads allowed)
				(copperpour not_allowed)
				(footprints allowed)
			)
			(placement
				(enabled no)
				(sheetname "")
			)
			(fill
				(thermal_gap 0.5)
				(thermal_bridge_width 0.5)
				(island_removal_mode 0)
			)
			(polygon
				(pts
					(xy 327.279 -60.833) (xy 327.279 -61.341) (xy 327.66 -61.341) (xy 327.66 -60.833)
				)
			)
		)
		(zone
			(layer "B.Cu")
			(hatch none 0.5)
			(connect_pads
				(clearance 0)
			)
			(min_thickness 0.25)
			(keepout
				(tracks allowed)
				(vias not_allowed)
				(pads allowed)
				(copperpour not_allowed)
				(footprints allowed)
			)
			(placement
				(enabled no)
				(sheetname "")
			)
			(fill
				(thermal_gap 0.5)
				(thermal_bridge_width 0.5)
				(island_removal_mode 0)
			)
			(polygon
				(pts
					(xy 327.66 -60.833) (xy 327.66 -61.341) (xy 327.279 -61.341) (xy 327.279 -60.833)
				)
			)
		)
	)
)
